# S9S_MB_2U (Grand Teton) — schematic netlist excerpt (pin names and nets, part order shuffled) for the footprints in the layout excerpt that follows; sources: Cadence DE-HDL packaged netlist, KiCad conversion of 03242023_DA0F0TMBIJ0_F0T_Motherboard_J_brd_V01_OCP.brd

C1305  Q_CAP  0.1UF 25V 10% X7R  pkg 0402  page 194 : A = P3V3_AUX ; B = GND
R3435  Q_RES  4.7K 5% CHIP  pkg 0402LF  page 147 : A = P3V3_AUX ; B = GPU_FPGA_OVERT

(kicad_pcb
	(version 20260206)
	(generator "pcbnew")
	(generator_version "10.0")
	(general
		(thickness 1.6)
		(legacy_teardrops no)
	)
	(paper "A4")
	(title_block
		(title "03242023_DA0F0TMBIJ0_F0T_Motherboard_J_brd_V01_OCP.brd")
		(comment 1 "Grand Teton / footprints 2648-2649 of 6105")
	)
	(layers
		(0 "F.Cu" signal "TOP")
		(4 "In1.Cu" signal "GND")
		(6 "In2.Cu" signal "IN1")
		(8 "In3.Cu" signal "GND1")
		(10 "In4.Cu" signal "IN2")
		(12 "In5.Cu" signal "GND2")
		(14 "In6.Cu" signal "IN3")
		(16 "In7.Cu" signal "GND3")
		(18 "In8.Cu" signal "VCC")
		(20 "In9.Cu" signal "VCC1")
		(22 "In10.Cu" signal "GND4")
		(24 "In11.Cu" signal "IN4")
		(26 "In12.Cu" signal "GND5")
		(28 "In13.Cu" signal "IN5")
		(30 "In14.Cu" signal "GND6")
		(32 "In15.Cu" signal "IN6")
		(34 "In16.Cu" signal "GND7")
		(2 "B.Cu" signal "BOTTOM")
		(9 "F.Adhes" user "F.Adhesive")
		(11 "B.Adhes" user "B.Adhesive")
		(13 "F.Paste" user "Package Geometry/Pastemask Top")
		(15 "B.Paste" user "Package Geometry/Pastemask Bottom")
		(5 "F.SilkS" user "Ref Des/Silkscreen Top")
		(7 "B.SilkS" user "Ref Des/Silkscreen Bottom")
		(1 "F.Mask" user "Board Geometry/Soldermask Top")
		(3 "B.Mask" user "Board Geometry/Soldermask Bottom")
		(17 "Dwgs.User" user "User.Drawings")
		(19 "Cmts.User" user "User.Comments")
		(21 "Eco1.User" user "User.Eco1")
		(23 "Eco2.User" user "User.Eco2")
		(25 "Edge.Cuts" user "Board Geometry/Outline")
		(27 "Margin" user)
		(31 "F.CrtYd" user "Package Geometry/Place Bound Top")
		(29 "B.CrtYd" user "Package Geometry/Place Bound Bottom")
		(35 "F.Fab" user "Ref Des/Assembly Top")
		(33 "B.Fab" user "Ref Des/Assembly Bottom")
	)
	(footprint ""
		(layer "F.Cu")
		(at 159.82188 -59.527948 180)
		(property "Reference" "C1305"
			(at 0 0 180)
			(layer "F.SilkS")
			(hide yes)
			(effects
				(font
					(size 1.27 1.27)
				)
			)
		)
		(property "Value" ""
			(at 0 0 180)
			(layer "F.Fab")
			(effects
				(font
					(size 1.27 1.27)
				)
			)
		)
		(duplicate_pad_numbers_are_jumpers no)
		(fp_line
			(start 0.7874 0.4064)
			(end -0.7874 0.4064)
			(stroke
				(width 0.1524)
				(type default)
			)
			(layer "F.SilkS")
		)
		(fp_line
			(start 0.7874 -0.4064)
			(end 0.7874 0.4064)
			(stroke
				(width 0.1524)
				(type default)
			)
			(layer "F.SilkS")
		)
		(fp_line
			(start -0.7874 0.4064)
			(end -0.7874 -0.4064)
			(stroke
				(width 0.1524)
				(type default)
			)
			(layer "F.SilkS")
		)
		(fp_line
			(start -0.7874 -0.4064)
			(end 0.7874 -0.4064)
			(stroke
				(width 0.1524)
				(type default)
			)
			(layer "F.SilkS")
		)
		(fp_line
			(start 0.67945 0.3048)
			(end 0.120396 0.3048)
			(stroke
				(width 0.1)
				(type default)
			)
			(layer "F.Fab")
		)
		(fp_line
			(start 0.67945 -0.3048)
			(end 0.67945 0.3048)
			(stroke
				(width 0.1)
				(type default)
			)
			(layer "F.Fab")
		)
		(fp_line
			(start 0.12065 -0.2794)
			(end 0.12065 -0.3048)
			(stroke
				(width 0.1)
				(type default)
			)
			(layer "F.Fab")
		)
		(fp_line
			(start 0.12065 -0.3048)
			(end 0.67945 -0.3048)
			(stroke
				(width 0.1)
				(type default)
			)
			(layer "F.Fab")
		)
		(fp_line
			(start 0.120396 0.3048)
			(end 0.120396 0.2794)
			(stroke
				(width 0.1)
				(type default)
			)
			(layer "F.Fab")
		)
		(fp_line
			(start 0.120396 0.2794)
			(end -0.12065 0.2794)
			(stroke
				(width 0.1)
				(type default)
			)
			(layer "F.Fab")
		)
		(fp_line
			(start -0.12065 0.3048)
			(end -0.67945 0.3048)
			(stroke
				(width 0.1)
				(type default)
			)
			(layer "F.Fab")
		)
		(fp_line
			(start -0.12065 0.2794)
			(end -0.12065 0.3048)
			(stroke
				(width 0.1)
				(type default)
			)
			(layer "F.Fab")
		)
		(fp_line
			(start -0.12065 -0.2794)
			(end 0.12065 -0.2794)
			(stroke
				(width 0.1)
				(type default)
			)
			(layer "F.Fab")
		)
		(fp_line
			(start -0.12065 -0.305054)
			(end -0.12065 -0.2794)
			(stroke
				(width 0.1)
				(type default)
			)
			(layer "F.Fab")
		)
		(fp_line
			(start -0.67945 0.3048)
			(end -0.67945 -0.305054)
			(stroke
				(width 0.1)
				(type default)
			)
			(layer "F.Fab")
		)
		(fp_line
			(start -0.67945 -0.305054)
			(end -0.12065 -0.305054)
			(stroke
				(width 0.1)
				(type default)
			)
			(layer "F.Fab")
		)
		(pad "1" smd circle
			(at -0.40005 0 180)
			(size 0 0)
			(layers "F.Cu" "F.Mask" "F.Paste")
			(net "P3V3_AUX")
		)
		(pad "2" smd circle
			(at 0.40005 0 180)
			(size 0 0)
			(layers "F.Cu" "F.Mask" "F.Paste")
			(net "GND")
		)
	)
	(footprint ""
		(layer "F.Cu")
		(at 432.061112 -397.270478 180)
		(property "Reference" "R3435"
			(at 0 0 180)
			(layer "F.SilkS")
			(hide yes)
			(effects
				(font
					(size 1.27 1.27)
				)
			)
		)
		(property "Value" ""
			(at 0 0 180)
			(layer "F.Fab")
			(effects
				(font
					(size 1.27 1.27)
				)
			)
		)
		(duplicate_pad_numbers_are_jumpers no)
		(fp_line
			(start 0.7874 0.4064)
			(end -0.7874 0.4064)
			(stroke
				(width 0.1524)
				(type default)
			)
			(layer "F.SilkS")
		)
		(fp_line
			(start 0.7874 -0.4064)
			(end 0.7874 0.4064)
			(stroke
				(width 0.1524)
				(type default)
			)
			(layer "F.SilkS")
		)
		(fp_line
			(start -0.7874 0.4064)
			(end -0.7874 -0.4064)
			(stroke
				(width 0.1524)
				(type default)
			)
			(layer "F.SilkS")
		)
		(fp_line
			(start -0.7874 -0.4064)
			(end 0.7874 -0.4064)
			(stroke
				(width 0.1524)
				(type default)
			)
			(layer "F.SilkS")
		)
		(fp_line
			(start 0.67945 0.3048)
			(end 0.120396 0.3048)
			(stroke
				(width 0.1)
				(type default)
			)
			(layer "F.Fab")
		)
		(fp_line
			(start 0.67945 -0.3048)
			(end 0.67945 0.3048)
			(stroke
				(width 0.1)
				(type default)
			)
			(layer "F.Fab")
		)
		(fp_line
			(start 0.12065 -0.2794)
			(end 0.12065 -0.3048)
			(stroke
				(width 0.1)
				(type default)
			)
			(layer "F.Fab")
		)
		(fp_line
			(start 0.12065 -0.3048)
			(end 0.67945 -0.3048)
			(stroke
				(width 0.1)
				(type default)
			)
			(layer "F.Fab")
		)
		(fp_line
			(start 0.120396 0.3048)
			(end 0.120396 0.2794)
			(stroke
				(width 0.1)
				(type default)
			)
			(layer "F.Fab")
		)
		(fp_line
			(start 0.120396 0.2794)
			(end -0.12065 0.2794)
			(stroke
				(width 0.1)
				(type default)
			)
			(layer "F.Fab")
		)
		(fp_line
			(start -0.12065 0.3048)
			(end -0.67945 0.3048)
			(stroke
				(width 0.1)
				(type default)
			)
			(layer "F.Fab")
		)
		(fp_line
			(start -0.12065 0.2794)
			(end -0.12065 0.3048)
			(stroke
				(width 0.1)
				(type default)
			)
			(layer "F.Fab")
		)
		(fp_line
			(start -0.12065 -0.2794)
			(end 0.12065 -0.2794)
			(stroke
				(width 0.1)
				(type default)
			)
			(layer "F.Fab")
		)
		(fp_line
			(start -0.12065 -0.305054)
			(end -0.12065 -0.2794)
			(stroke
				(width 0.1)
				(type default)
			)
			(layer "F.Fab")
		)
		(fp_line
			(start -0.67945 0.3048)
			(end -0.67945 -0.305054)
			(stroke
				(width 0.1)
				(type default)
			)
			(layer "F.Fab")
		)
		(fp_line
			(start -0.67945 -0.305054)
			(end -0.12065 -0.305054)
			(stroke
				(width 0.1)
				(type default)
			)
			(layer "F.Fab")
		)
		(pad "1" smd circle
			(at -0.40005 0 180)
			(size 0 0)
			(layers "F.Cu" "F.Mask" "F.Paste")
			(net "P3V3_AUX")
		)
		(pad "2" smd circle
			(at 0.40005 0 180)
			(size 0 0)
			(layers "F.Cu" "F.Mask" "F.Paste")
			(net "GPU_FPGA_OVERT")
		)
	)
)
